(kicad_pcb
	(version 20260206)
	(generator "pcbnew")
	(generator_version "10.0")
	(general
		(thickness 1.6)
		(legacy_teardrops no)
	)
	(paper "A4")
	(title_block
		(title "04192023_DAF0TMB3IC0_F0TG_MB_C_brd_V02_OCP.brd")
		(comment 1 "Grand Teton / footprints 5022-5028 of 8354")
	)
	(layers
		(0 "F.Cu" signal "TOP")
		(4 "In1.Cu" signal "GND")
		(6 "In2.Cu" signal "IN1")
		(8 "In3.Cu" signal "GND1")
		(10 "In4.Cu" signal "IN2")
		(12 "In5.Cu" signal "GND2")
		(14 "In6.Cu" signal "IN3")
		(16 "In7.Cu" signal "GND3")
		(18 "In8.Cu" signal "VCC")
		(20 "In9.Cu" signal "VCC1")
		(22 "In10.Cu" signal "GND4")
		(24 "In11.Cu" signal "IN4")
		(26 "In12.Cu" signal "GND5")
		(28 "In13.Cu" signal "IN5")
		(30 "In14.Cu" signal "GND6")
		(32 "In15.Cu" signal "IN6")
		(34 "In16.Cu" signal "GND7")
		(2 "B.Cu" signal "BOTTOM")
		(9 "F.Adhes" user "F.Adhesive")
		(11 "B.Adhes" user "B.Adhesive")
		(13 "F.Paste" user "Package Geometry/Pastemask Top")
		(15 "B.Paste" user "Package Geometry/Pastemask Bottom")
		(5 "F.SilkS" user "Ref Des/Silkscreen Top")
		(7 "B.SilkS" user "Ref Des/Silkscreen Bottom")
		(1 "F.Mask" user "Board Geometry/Soldermask Top")
		(3 "B.Mask" user "Board Geometry/Soldermask Bottom")
		(17 "Dwgs.User" user "User.Drawings")
		(19 "Cmts.User" user "User.Comments")
		(21 "Eco1.User" user "User.Eco1")
		(23 "Eco2.User" user "User.Eco2")
		(25 "Edge.Cuts" user "Board Geometry/Outline")
		(27 "Margin" user)
		(31 "F.CrtYd" user "Package Geometry/Place Bound Top")
		(29 "B.CrtYd" user "Package Geometry/Place Bound Bottom")
		(35 "F.Fab" user "Ref Des/Assembly Top")
		(33 "B.Fab" user "Ref Des/Assembly Bottom")
	)
	(footprint ""
		(layer "B.Cu")
		(at 87.118952 -390.560052 90)
		(property "Reference" "C333"
			(at 0 0 90)
			(layer "B.SilkS")
			(hide yes)
			(effects
				(font
					(size 1.27 1.27)
				)
				(justify mirror)
			)
		)
		(property "Value" ""
			(at 0 0 90)
			(layer "B.Fab")
			(effects
				(font
					(size 1.27 1.27)
				)
				(justify mirror)
			)
		)
		(duplicate_pad_numbers_are_jumpers no)
		(fp_line
			(start 0.7874 -0.4064)
			(end -0.7874 -0.4064)
			(stroke
				(width 0.1524)
				(type default)
			)
			(layer "B.SilkS")
		)
		(fp_line
			(start -0.7874 -0.4064)
			(end -0.7874 0.4064)
			(stroke
				(width 0.1524)
				(type default)
			)
			(layer "B.SilkS")
		)
		(fp_line
			(start 0.7874 0.4064)
			(end 0.7874 -0.4064)
			(stroke
				(width 0.1524)
				(type default)
			)
			(layer "B.SilkS")
		)
		(fp_line
			(start -0.7874 0.4064)
			(end 0.7874 0.4064)
			(stroke
				(width 0.1524)
				(type default)
			)
			(layer "B.SilkS")
		)
		(fp_line
			(start 0.67945 -0.305054)
			(end 0.12065 -0.305054)
			(stroke
				(width 0.1)
				(type default)
			)
			(layer "B.Fab")
		)
		(fp_line
			(start 0.12065 -0.305054)
			(end 0.12065 -0.2794)
			(stroke
				(width 0.1)
				(type default)
			)
			(layer "B.Fab")
		)
		(fp_line
			(start -0.12065 -0.3048)
			(end -0.67945 -0.3048)
			(stroke
				(width 0.1)
				(type default)
			)
			(layer "B.Fab")
		)
		(fp_line
			(start -0.67945 -0.3048)
			(end -0.67945 0.3048)
			(stroke
				(width 0.1)
				(type default)
			)
			(layer "B.Fab")
		)
		(fp_line
			(start 0.12065 -0.2794)
			(end -0.12065 -0.2794)
			(stroke
				(width 0.1)
				(type default)
			)
			(layer "B.Fab")
		)
		(fp_line
			(start -0.12065 -0.2794)
			(end -0.12065 -0.3048)
			(stroke
				(width 0.1)
				(type default)
			)
			(layer "B.Fab")
		)
		(fp_line
			(start 0.12065 0.2794)
			(end 0.12065 0.3048)
			(stroke
				(width 0.1)
				(type default)
			)
			(layer "B.Fab")
		)
		(fp_line
			(start -0.120396 0.2794)
			(end 0.12065 0.2794)
			(stroke
				(width 0.1)
				(type default)
			)
			(layer "B.Fab")
		)
		(fp_line
			(start 0.67945 0.3048)
			(end 0.67945 -0.305054)
			(stroke
				(width 0.1)
				(type default)
			)
			(layer "B.Fab")
		)
		(fp_line
			(start 0.12065 0.3048)
			(end 0.67945 0.3048)
			(stroke
				(width 0.1)
				(type default)
			)
			(layer "B.Fab")
		)
		(fp_line
			(start -0.120396 0.3048)
			(end -0.120396 0.2794)
			(stroke
				(width 0.1)
				(type default)
			)
			(layer "B.Fab")
		)
		(fp_line
			(start -0.67945 0.3048)
			(end -0.120396 0.3048)
			(stroke
				(width 0.1)
				(type default)
			)
			(layer "B.Fab")
		)
		(pad "1" smd circle
			(at 0.40005 0 270)
			(size 0 0)
			(layers "B.Cu" "B.Mask" "B.Paste")
			(net "P0V9_CPU1_RT_2D")
		)
		(pad "2" smd circle
			(at -0.40005 0 270)
			(size 0 0)
			(layers "B.Cu" "B.Mask" "B.Paste")
			(net "GND")
		)
	)
	(footprint ""
		(layer "B.Cu")
		(at 284.074108 -420.491412 90)
		(property "Reference" "C2334"
			(at 0 0 90)
			(layer "B.SilkS")
			(hide yes)
			(effects
				(font
					(size 1.27 1.27)
				)
				(justify mirror)
			)
		)
		(property "Value" ""
			(at 0 0 90)
			(layer "B.Fab")
			(effects
				(font
					(size 1.27 1.27)
				)
				(justify mirror)
			)
		)
		(duplicate_pad_numbers_are_jumpers no)
		(fp_line
			(start 0.7874 -0.4064)
			(end -0.7874 -0.4064)
			(stroke
				(width 0.1524)
				(type default)
			)
			(layer "B.SilkS")
		)
		(fp_line
			(start -0.7874 -0.4064)
			(end -0.7874 0.4064)
			(stroke
				(width 0.1524)
				(type default)
			)
			(layer "B.SilkS")
		)
		(fp_line
			(start 0.7874 0.4064)
			(end 0.7874 -0.4064)
			(stroke
				(width 0.1524)
				(type default)
			)
			(layer "B.SilkS")
		)
		(fp_line
			(start -0.7874 0.4064)
			(end 0.7874 0.4064)
			(stroke
				(width 0.1524)
				(type default)
			)
			(layer "B.SilkS")
		)
		(fp_line
			(start 0.67945 -0.305054)
			(end 0.12065 -0.305054)
			(stroke
				(width 0.1)
				(type default)
			)
			(layer "B.Fab")
		)
		(fp_line
			(start 0.12065 -0.305054)
			(end 0.12065 -0.2794)
			(stroke
				(width 0.1)
				(type default)
			)
			(layer "B.Fab")
		)
		(fp_line
			(start -0.12065 -0.3048)
			(end -0.67945 -0.3048)
			(stroke
				(width 0.1)
				(type default)
			)
			(layer "B.Fab")
		)
		(fp_line
			(start -0.67945 -0.3048)
			(end -0.67945 0.3048)
			(stroke
				(width 0.1)
				(type default)
			)
			(layer "B.Fab")
		)
		(fp_line
			(start 0.12065 -0.2794)
			(end -0.12065 -0.2794)
			(stroke
				(width 0.1)
				(type default)
			)
			(layer "B.Fab")
		)
		(fp_line
			(start -0.12065 -0.2794)
			(end -0.12065 -0.3048)
			(stroke
				(width 0.1)
				(type default)
			)
			(layer "B.Fab")
		)
		(fp_line
			(start 0.12065 0.2794)
			(end 0.12065 0.3048)
			(stroke
				(width 0.1)
				(type default)
			)
			(layer "B.Fab")
		)
		(fp_line
			(start -0.120396 0.2794)
			(end 0.12065 0.2794)
			(stroke
				(width 0.1)
				(type default)
			)
			(layer "B.Fab")
		)
		(fp_line
			(start 0.67945 0.3048)
			(end 0.67945 -0.305054)
			(stroke
				(width 0.1)
				(type default)
			)
			(layer "B.Fab")
		)
		(fp_line
			(start 0.12065 0.3048)
			(end 0.67945 0.3048)
			(stroke
				(width 0.1)
				(type default)
			)
			(layer "B.Fab")
		)
		(fp_line
			(start -0.120396 0.3048)
			(end -0.120396 0.2794)
			(stroke
				(width 0.1)
				(type default)
			)
			(layer "B.Fab")
		)
		(fp_line
			(start -0.67945 0.3048)
			(end -0.120396 0.3048)
			(stroke
				(width 0.1)
				(type default)
			)
			(layer "B.Fab")
		)
		(pad "1" smd circle
			(at 0.40005 0 270)
			(size 0 0)
			(layers "B.Cu" "B.Mask" "B.Paste")
			(net "P3V3_9ZXL045_P0_VDDA")
		)
		(pad "2" smd circle
			(at -0.40005 0 270)
			(size 0 0)
			(layers "B.Cu" "B.Mask" "B.Paste")
			(net "GND")
		)
	)
	(footprint ""
		(layer "B.Cu")
		(at 363.550454 -251.78131)
		(property "Reference" "C2550"
			(at 0 0 0)
			(layer "B.SilkS")
			(hide yes)
			(effects
				(font
					(size 1.27 1.27)
				)
				(justify mirror)
			)
		)
		(property "Value" ""
			(at 0 0 0)
			(layer "B.Fab")
			(effects
				(font
					(size 1.27 1.27)
				)
				(justify mirror)
			)
		)
		(duplicate_pad_numbers_are_jumpers no)
		(fp_line
			(start -0.7874 -0.4064)
			(end -0.7874 0.4064)
			(stroke
				(width 0.1524)
				(type default)
			)
			(layer "B.SilkS")
		)
		(fp_line
			(start -0.7874 0.4064)
			(end 0.7874 0.4064)
			(stroke
				(width 0.1524)
				(type default)
			)
			(layer "B.SilkS")
		)
		(fp_line
			(start 0.7874 -0.4064)
			(end -0.7874 -0.4064)
			(stroke
				(width 0.1524)
				(type default)
			)
			(layer "B.SilkS")
		)
		(fp_line
			(start 0.7874 0.4064)
			(end 0.7874 -0.4064)
			(stroke
				(width 0.1524)
				(type default)
			)
			(layer "B.SilkS")
		)
		(fp_line
			(start -0.67945 -0.3048)
			(end -0.67945 0.3048)
			(stroke
				(width 0.1)
				(type default)
			)
			(layer "B.Fab")
		)
		(fp_line
			(start -0.67945 0.3048)
			(end -0.120396 0.3048)
			(stroke
				(width 0.1)
				(type default)
			)
			(layer "B.Fab")
		)
		(fp_line
			(start -0.12065 -0.3048)
			(end -0.67945 -0.3048)
			(stroke
				(width 0.1)
				(type default)
			)
			(layer "B.Fab")
		)
		(fp_line
			(start -0.12065 -0.2794)
			(end -0.12065 -0.3048)
			(stroke
				(width 0.1)
				(type default)
			)
			(layer "B.Fab")
		)
		(fp_line
			(start -0.120396 0.2794)
			(end 0.12065 0.2794)
			(stroke
				(width 0.1)
				(type default)
			)
			(layer "B.Fab")
		)
		(fp_line
			(start -0.120396 0.3048)
			(end -0.120396 0.2794)
			(stroke
				(width 0.1)
				(type default)
			)
			(layer "B.Fab")
		)
		(fp_line
			(start 0.12065 -0.305054)
			(end 0.12065 -0.2794)
			(stroke
				(width 0.1)
				(type default)
			)
			(layer "B.Fab")
		)
		(fp_line
			(start 0.12065 -0.2794)
			(end -0.12065 -0.2794)
			(stroke
				(width 0.1)
				(type default)
			)
			(layer "B.Fab")
		)
		(fp_line
			(start 0.12065 0.2794)
			(end 0.12065 0.3048)
			(stroke
				(width 0.1)
				(type default)
			)
			(layer "B.Fab")
		)
		(fp_line
			(start 0.12065 0.3048)
			(end 0.67945 0.3048)
			(stroke
				(width 0.1)
				(type default)
			)
			(layer "B.Fab")
		)
		(fp_line
			(start 0.67945 -0.305054)
			(end 0.12065 -0.305054)
			(stroke
				(width 0.1)
				(type default)
			)
			(layer "B.Fab")
		)
		(fp_line
			(start 0.67945 0.3048)
			(end 0.67945 -0.305054)
			(stroke
				(width 0.1)
				(type default)
			)
			(layer "B.Fab")
		)
		(pad "1" smd circle
			(at 0.40005 0 180)
			(size 0 0)
			(layers "B.Cu" "B.Mask" "B.Paste")
			(net "PVDDCR_SOC_P0")
		)
		(pad "2" smd circle
			(at -0.40005 0 180)
			(size 0 0)
			(layers "B.Cu" "B.Mask" "B.Paste")
			(net "GND")
		)
	)
	(footprint ""
		(layer "B.Cu")
		(at 163.806378 -386.766562 90)
		(property "Reference" "C422"
			(at 0 0 90)
			(layer "B.SilkS")
			(hide yes)
			(effects
				(font
					(size 1.27 1.27)
				)
				(justify mirror)
			)
		)
		(property "Value" ""
			(at 0 0 90)
			(layer "B.Fab")
			(effects
				(font
					(size 1.27 1.27)
				)
				(justify mirror)
			)
		)
		(duplicate_pad_numbers_are_jumpers no)
		(fp_line
			(start 0.299974 -0.150114)
			(end -0.299974 -0.150114)
			(stroke
				(width 0.1)
				(type default)
			)
			(layer "B.Fab")
		)
		(fp_line
			(start -0.299974 -0.150114)
			(end -0.299974 0.150114)
			(stroke
				(width 0.1)
				(type default)
			)
			(layer "B.Fab")
		)
		(fp_line
			(start 0.299974 0.150114)
			(end 0.299974 -0.150114)
			(stroke
				(width 0.1)
				(type default)
			)
			(layer "B.Fab")
		)
		(fp_line
			(start -0.299974 0.150114)
			(end 0.299974 0.150114)
			(stroke
				(width 0.1)
				(type default)
			)
			(layer "B.Fab")
		)
		(pad "1" smd rect
			(at 0.2667 0 270)
			(size 0.3048 0.381)
			(layers "B.Cu" "B.Mask" "B.Paste")
			(net "P0V9_CPU1_RT2_2A")
		)
		(pad "2" smd rect
			(at -0.2667 0 270)
			(size 0.3048 0.381)
			(layers "B.Cu" "B.Mask" "B.Paste")
			(net "GND")
		)
	)
	(footprint ""
		(layer "B.Cu")
		(at 353.900232 -262.204962)
		(property "Reference" "C3935"
			(at 0 0 0)
			(layer "B.SilkS")
			(hide yes)
			(effects
				(font
					(size 1.27 1.27)
				)
				(justify mirror)
			)
		)
		(property "Value" ""
			(at 0 0 0)
			(layer "B.Fab")
			(effects
				(font
					(size 1.27 1.27)
				)
				(justify mirror)
			)
		)
		(duplicate_pad_numbers_are_jumpers no)
		(fp_line
			(start -0.7874 -0.4064)
			(end -0.7874 0.4064)
			(stroke
				(width 0.1524)
				(type default)
			)
			(layer "B.SilkS")
		)
		(fp_line
			(start -0.7874 0.4064)
			(end 0.7874 0.4064)
			(stroke
				(width 0.1524)
				(type default)
			)
			(layer "B.SilkS")
		)
		(fp_line
			(start 0.7874 -0.4064)
			(end -0.7874 -0.4064)
			(stroke
				(width 0.1524)
				(type default)
			)
			(layer "B.SilkS")
		)
		(fp_line
			(start 0.7874 0.4064)
			(end 0.7874 -0.4064)
			(stroke
				(width 0.1524)
				(type default)
			)
			(layer "B.SilkS")
		)
		(fp_line
			(start -0.67945 -0.3048)
			(end -0.67945 0.3048)
			(stroke
				(width 0.1)
				(type default)
			)
			(layer "B.Fab")
		)
		(fp_line
			(start -0.67945 0.3048)
			(end -0.120396 0.3048)
			(stroke
				(width 0.1)
				(type default)
			)
			(layer "B.Fab")
		)
		(fp_line
			(start -0.12065 -0.3048)
			(end -0.67945 -0.3048)
			(stroke
				(width 0.1)
				(type default)
			)
			(layer "B.Fab")
		)
		(fp_line
			(start -0.12065 -0.2794)
			(end -0.12065 -0.3048)
			(stroke
				(width 0.1)
				(type default)
			)
			(layer "B.Fab")
		)
		(fp_line
			(start -0.120396 0.2794)
			(end 0.12065 0.2794)
			(stroke
				(width 0.1)
				(type default)
			)
			(layer "B.Fab")
		)
		(fp_line
			(start -0.120396 0.3048)
			(end -0.120396 0.2794)
			(stroke
				(width 0.1)
				(type default)
			)
			(layer "B.Fab")
		)
		(fp_line
			(start 0.12065 -0.305054)
			(end 0.12065 -0.2794)
			(stroke
				(width 0.1)
				(type default)
			)
			(layer "B.Fab")
		)
		(fp_line
			(start 0.12065 -0.2794)
			(end -0.12065 -0.2794)
			(stroke
				(width 0.1)
				(type default)
			)
			(layer "B.Fab")
		)
		(fp_line
			(start 0.12065 0.2794)
			(end 0.12065 0.3048)
			(stroke
				(width 0.1)
				(type default)
			)
			(layer "B.Fab")
		)
		(fp_line
			(start 0.12065 0.3048)
			(end 0.67945 0.3048)
			(stroke
				(width 0.1)
				(type default)
			)
			(layer "B.Fab")
		)
		(fp_line
			(start 0.67945 -0.305054)
			(end 0.12065 -0.305054)
			(stroke
				(width 0.1)
				(type default)
			)
			(layer "B.Fab")
		)
		(fp_line
			(start 0.67945 0.3048)
			(end 0.67945 -0.305054)
			(stroke
				(width 0.1)
				(type default)
			)
			(layer "B.Fab")
		)
		(pad "1" smd circle
			(at 0.40005 0 180)
			(size 0 0)
			(layers "B.Cu" "B.Mask" "B.Paste")
			(net "PVDD11_S3_P0")
		)
		(pad "2" smd circle
			(at -0.40005 0 180)
			(size 0 0)
			(layers "B.Cu" "B.Mask" "B.Paste")
			(net "GND")
		)
	)
	(footprint ""
		(layer "B.Cu")
		(at 167.116252 -115.28552)
		(property "Reference" "R993"
			(at 0 0 0)
			(layer "B.SilkS")
			(hide yes)
			(effects
				(font
					(size 1.27 1.27)
				)
				(justify mirror)
			)
		)
		(property "Value" ""
			(at 0 0 0)
			(layer "B.Fab")
			(effects
				(font
					(size 1.27 1.27)
				)
				(justify mirror)
			)
		)
		(duplicate_pad_numbers_are_jumpers no)
		(fp_line
			(start -0.7874 -0.4064)
			(end -0.7874 0.4064)
			(stroke
				(width 0.1524)
				(type default)
			)
			(layer "B.SilkS")
		)
		(fp_line
			(start -0.7874 0.4064)
			(end 0.7874 0.4064)
			(stroke
				(width 0.1524)
				(type default)
			)
			(layer "B.SilkS")
		)
		(fp_line
			(start 0.7874 -0.4064)
			(end -0.7874 -0.4064)
			(stroke
				(width 0.1524)
				(type default)
			)
			(layer "B.SilkS")
		)
		(fp_line
			(start 0.7874 0.4064)
			(end 0.7874 -0.4064)
			(stroke
				(width 0.1524)
				(type default)
			)
			(layer "B.SilkS")
		)
		(fp_line
			(start -0.67945 -0.3048)
			(end -0.67945 0.3048)
			(stroke
				(width 0.1)
				(type default)
			)
			(layer "B.Fab")
		)
		(fp_line
			(start -0.67945 0.3048)
			(end -0.120396 0.3048)
			(stroke
				(width 0.1)
				(type default)
			)
			(layer "B.Fab")
		)
		(fp_line
			(start -0.12065 -0.3048)
			(end -0.67945 -0.3048)
			(stroke
				(width 0.1)
				(type default)
			)
			(layer "B.Fab")
		)
		(fp_line
			(start -0.12065 -0.2794)
			(end -0.12065 -0.3048)
			(stroke
				(width 0.1)
				(type default)
			)
			(layer "B.Fab")
		)
		(fp_line
			(start -0.120396 0.2794)
			(end 0.12065 0.2794)
			(stroke
				(width 0.1)
				(type default)
			)
			(layer "B.Fab")
		)
		(fp_line
			(start -0.120396 0.3048)
			(end -0.120396 0.2794)
			(stroke
				(width 0.1)
				(type default)
			)
			(layer "B.Fab")
		)
		(fp_line
			(start 0.12065 -0.305054)
			(end 0.12065 -0.2794)
			(stroke
				(width 0.1)
				(type default)
			)
			(layer "B.Fab")
		)
		(fp_line
			(start 0.12065 -0.2794)
			(end -0.12065 -0.2794)
			(stroke
				(width 0.1)
				(type default)
			)
			(layer "B.Fab")
		)
		(fp_line
			(start 0.12065 0.2794)
			(end 0.12065 0.3048)
			(stroke
				(width 0.1)
				(type default)
			)
			(layer "B.Fab")
		)
		(fp_line
			(start 0.12065 0.3048)
			(end 0.67945 0.3048)
			(stroke
				(width 0.1)
				(type default)
			)
			(layer "B.Fab")
		)
		(fp_line
			(start 0.67945 -0.305054)
			(end 0.12065 -0.305054)
			(stroke
				(width 0.1)
				(type default)
			)
			(layer "B.Fab")
		)
		(fp_line
			(start 0.67945 0.3048)
			(end 0.67945 -0.305054)
			(stroke
				(width 0.1)
				(type default)
			)
			(layer "B.Fab")
		)
		(pad "1" smd circle
			(at 0.40005 0 180)
			(size 0 0)
			(layers "B.Cu" "B.Mask" "B.Paste")
			(net "FM_SYS_THROTTLE_N")
		)
		(pad "2" smd circle
			(at -0.40005 0 180)
			(size 0 0)
			(layers "B.Cu" "B.Mask" "B.Paste")
			(net "P3V3_AUX")
		)
	)
	(footprint ""
		(layer "B.Cu")
		(at 53.09362 -422.777666)
		(property "Reference" "R3318"
			(at 0 0 0)
			(layer "B.SilkS")
			(hide yes)
			(effects
				(font
					(size 1.27 1.27)
				)
				(justify mirror)
			)
		)
		(property "Value" ""
			(at 0 0 0)
			(layer "B.Fab")
			(effects
				(font
					(size 1.27 1.27)
				)
				(justify mirror)
			)
		)
		(duplicate_pad_numbers_are_jumpers no)
		(fp_line
			(start -0.7874 -0.4064)
			(end -0.7874 0.4064)
			(stroke
				(width 0.1524)
				(type default)
			)
			(layer "B.SilkS")
		)
		(fp_line
			(start -0.7874 0.4064)
			(end 0.7874 0.4064)
			(stroke
				(width 0.1524)
				(type default)
			)
			(layer "B.SilkS")
		)
		(fp_line
			(start 0.7874 -0.4064)
			(end -0.7874 -0.4064)
			(stroke
				(width 0.1524)
				(type default)
			)
			(layer "B.SilkS")
		)
		(fp_line
			(start 0.7874 0.4064)
			(end 0.7874 -0.4064)
			(stroke
				(width 0.1524)
				(type default)
			)
			(layer "B.SilkS")
		)
		(fp_line
			(start -0.67945 -0.3048)
			(end -0.67945 0.3048)
			(stroke
				(width 0.1)
				(type default)
			)
			(layer "B.Fab")
		)
		(fp_line
			(start -0.67945 0.3048)
			(end -0.120396 0.3048)
			(stroke
				(width 0.1)
				(type default)
			)
			(layer "B.Fab")
		)
		(fp_line
			(start -0.12065 -0.3048)
			(end -0.67945 -0.3048)
			(stroke
				(width 0.1)
				(type default)
			)
			(layer "B.Fab")
		)
		(fp_line
			(start -0.12065 -0.2794)
			(end -0.12065 -0.3048)
			(stroke
				(width 0.1)
				(type default)
			)
			(layer "B.Fab")
		)
		(fp_line
			(start -0.120396 0.2794)
			(end 0.12065 0.2794)
			(stroke
				(width 0.1)
				(type default)
			)
			(layer "B.Fab")
		)
		(fp_line
			(start -0.120396 0.3048)
			(end -0.120396 0.2794)
			(stroke
				(width 0.1)
				(type default)
			)
			(layer "B.Fab")
		)
		(fp_line
			(start 0.12065 -0.305054)
			(end 0.12065 -0.2794)
			(stroke
				(width 0.1)
				(type default)
			)
			(layer "B.Fab")
		)
		(fp_line
			(start 0.12065 -0.2794)
			(end -0.12065 -0.2794)
			(stroke
				(width 0.1)
				(type default)
			)
			(layer "B.Fab")
		)
		(fp_line
			(start 0.12065 0.2794)
			(end 0.12065 0.3048)
			(stroke
				(width 0.1)
				(type default)
			)
			(layer "B.Fab")
		)
		(fp_line
			(start 0.12065 0.3048)
			(end 0.67945 0.3048)
			(stroke
				(width 0.1)
				(type default)
			)
			(layer "B.Fab")
		)
		(fp_line
			(start 0.67945 -0.305054)
			(end 0.12065 -0.305054)
			(stroke
				(width 0.1)
				(type default)
			)
			(layer "B.Fab")
		)
		(fp_line
			(start 0.67945 0.3048)
			(end 0.67945 -0.305054)
			(stroke
				(width 0.1)
				(type default)
			)
			(layer "B.Fab")
		)
		(pad "1" smd circle
			(at 0.40005 0 180)
			(size 0 0)
			(layers "B.Cu" "B.Mask" "B.Paste")
			(net "P3V3_AUX")
		)
		(pad "2" smd circle
			(at -0.40005 0 180)
			(size 0 0)
			(layers "B.Cu" "B.Mask" "B.Paste")
			(net "GPU_FPGA_READY")
		)
	)
)
